(kicad_pcb
	(version 20241229)
	(generator "pcbnew")
	(generator_version "9.0")
	(general
		(thickness 1.6)
		(legacy_teardrops no)
	)
	(paper "A4")
	(title_block
		(title "OCuLink to PCIe adapter")
		(date "2025-06-18")
		(rev "1.0.0")
		(company "Antmicro Ltd")
		(comment 1 "www.antmicro.com")
		(comment 9 "footprints 111-114 of 159")
	)
	(layers
		(0 "F.Cu" signal)
		(4 "In1.Cu" signal)
		(6 "In2.Cu" signal)
		(2 "B.Cu" signal)
		(9 "F.Adhes" user "F.Adhesive")
		(11 "B.Adhes" user "B.Adhesive")
		(13 "F.Paste" user)
		(15 "B.Paste" user)
		(5 "F.SilkS" user "F.Silkscreen")
		(7 "B.SilkS" user "B.Silkscreen")
		(1 "F.Mask" user)
		(3 "B.Mask" user)
		(17 "Dwgs.User" user "User.Drawings")
		(19 "Cmts.User" user "User.Comments")
		(21 "Eco1.User" user "User.Eco1")
		(23 "Eco2.User" user "User.Eco2")
		(25 "Edge.Cuts" user)
		(27 "Margin" user)
		(31 "F.CrtYd" user "F.Courtyard")
		(29 "B.CrtYd" user "B.Courtyard")
		(35 "F.Fab" user)
		(33 "B.Fab" user)
	)
	(footprint "antmicro-footprints:SOD-123FL"
		(layer "F.Cu")
		(at 143 135)
		(property "Reference" "D8"
			(at -3.8 0.3 180)
			(layer "F.SilkS")
			(effects
				(font
					(size 0.7 0.7)
					(thickness 0.15)
				)
				(justify left bottom)
			)
		)
		(property "Value" "SZSMF4L14AT3G"
			(at 0 1.967 0)
			(layer "F.Fab")
			(effects
				(font
					(size 0.7 0.7)
					(thickness 0.15)
				)
				(justify left bottom)
			)
		)
		(property "Datasheet" "https://www.mouser.com/datasheet/2/240/media-3320461.pdf"
			(at 0 0 0)
			(layer "F.Fab")
			(hide yes)
			(effects
				(font
					(size 1.27 1.27)
					(thickness 0.15)
				)
			)
		)
		(property "Description" "ESD, TVS Diode, 14V, UNI, 400W, SOD-123FL"
			(at 0 0 0)
			(layer "F.Fab")
			(hide yes)
			(effects
				(font
					(size 1.27 1.27)
					(thickness 0.15)
				)
			)
		)
		(property "MPN" "SZSMF4L12AT3G"
			(at 0 0 0)
			(unlocked yes)
			(layer "F.Fab")
			(hide yes)
			(effects
				(font
					(size 1 1)
					(thickness 0.15)
				)
			)
		)
		(property "Author" "Antmicro"
			(at 0 0 0)
			(unlocked yes)
			(layer "F.Fab")
			(hide yes)
			(effects
				(font
					(size 1 1)
					(thickness 0.15)
				)
			)
		)
		(property "License" "Apache-2.0"
			(at 0 0 0)
			(unlocked yes)
			(layer "F.Fab")
			(hide yes)
			(effects
				(font
					(size 1 1)
					(thickness 0.15)
				)
			)
		)
		(property "Manufacturer" "Littelfuse"
			(at 0 0 0)
			(unlocked yes)
			(layer "F.Fab")
			(hide yes)
			(effects
				(font
					(size 1 1)
					(thickness 0.15)
				)
			)
		)
		(sheetname "/Power/")
		(sheetfile "power.kicad_sch")
		(attr smd)
		(fp_line
			(start -2.3 -1.1)
			(end -2.3 1.1)
			(stroke
				(width 0.15)
				(type solid)
			)
			(layer "F.SilkS")
		)
		(fp_line
			(start -2.3 1.1)
			(end 0 1.1)
			(stroke
				(width 0.15)
				(type solid)
			)
			(layer "F.SilkS")
		)
		(fp_line
			(start 0 -1.1)
			(end -2.3 -1.1)
			(stroke
				(width 0.15)
				(type solid)
			)
			(layer "F.SilkS")
		)
		(fp_rect
			(start -2.35 -1.125)
			(end 2.35 1.125)
			(stroke
				(width 0.05)
				(type solid)
			)
			(fill no)
			(layer "F.CrtYd")
		)
		(fp_rect
			(start -1.825 -0.875)
			(end 1.824 0.873)
			(stroke
				(width 0.15)
				(type solid)
			)
			(fill no)
			(layer "F.Fab")
		)
		(fp_rect
			(start -0.775 -0.875)
			(end -0.525 0.875)
			(stroke
				(width 0.15)
				(type solid)
			)
			(fill yes)
			(layer "F.Fab")
		)
		(fp_text user "${REFERENCE}"
			(at 0 0 0)
			(layer "F.Fab")
			(effects
				(font
					(size 0.7 0.7)
					(thickness 0.15)
				)
				(justify left bottom)
			)
		)
		(fp_text user "License: Apache-2.0"
			(at -2.406 6.368 0)
			(layer "F.Fab")
			(effects
				(font
					(size 0.7 0.7)
					(thickness 0.15)
				)
				(justify left bottom)
			)
		)
		(fp_text user "Author: Antmicro"
			(at -2.406 5.168 0)
			(layer "F.Fab")
			(effects
				(font
					(size 0.7 0.7)
					(thickness 0.15)
				)
				(justify left bottom)
			)
		)
		(pad "1" smd roundrect
			(at -1.43 0)
			(size 1.34 1.8)
			(layers "F.Cu" "F.Mask" "F.Paste")
			(roundrect_rratio 0.14)
			(net 116 "/Power/Ideal-diode-2/VIN")
			(pinfunction "C")
			(pintype "passive")
		)
		(pad "2" smd roundrect
			(at 1.429 0)
			(size 1.34 1.8)
			(layers "F.Cu" "F.Mask" "F.Paste")
			(roundrect_rratio 0.14)
			(net 66 "GND")
			(pinfunction "A")
			(pintype "passive")
		)
	)
	(footprint "antmicro-footprints:R_0402_1005Metric"
		(layer "F.Cu")
		(at 143.8 64)
		(descr "Resistor SMD 0402")
		(tags "resistor SMD 0402")
		(property "Reference" "R55"
			(at -1.1 1.5 0)
			(layer "F.SilkS")
			(effects
				(font
					(size 0.7 0.7)
					(thickness 0.15)
				)
				(justify left bottom)
			)
		)
		(property "Value" "R_22R_0402"
			(at -1.011843 1.772047 0)
			(layer "F.Fab")
			(effects
				(font
					(size 0.7 0.7)
					(thickness 0.15)
				)
				(justify left bottom)
			)
		)
		(property "Datasheet" "https://www.bourns.com/docs/product-datasheets/cr.pdf"
			(at 0 0 0)
			(layer "F.Fab")
			(hide yes)
			(effects
				(font
					(size 1.27 1.27)
					(thickness 0.15)
				)
			)
		)
		(property "Description" "SMD Chip Resistor, 22 ohm, ± 1%, 62.5 mW, 0402 [1005 Metric], Thick Film, General Purpose"
			(at 0 0 0)
			(layer "F.Fab")
			(hide yes)
			(effects
				(font
					(size 1.27 1.27)
					(thickness 0.15)
				)
			)
		)
		(property "MPN" "CR0402-FX-22R0GLF"
			(at 0 0 0)
			(unlocked yes)
			(layer "F.Fab")
			(hide yes)
			(effects
				(font
					(size 1 1)
					(thickness 0.15)
				)
			)
		)
		(property "Manufacturer" "Bourns"
			(at 0 0 0)
			(unlocked yes)
			(layer "F.Fab")
			(hide yes)
			(effects
				(font
					(size 1 1)
					(thickness 0.15)
				)
			)
		)
		(property "License" "Apache-2.0"
			(at 0 0 0)
			(unlocked yes)
			(layer "F.Fab")
			(hide yes)
			(effects
				(font
					(size 1 1)
					(thickness 0.15)
				)
			)
		)
		(property "Author" "Antmicro"
			(at 0 0 0)
			(unlocked yes)
			(layer "F.Fab")
			(hide yes)
			(effects
				(font
					(size 1 1)
					(thickness 0.15)
				)
			)
		)
		(property "Val" "22R"
			(at 0 0 0)
			(unlocked yes)
			(layer "F.Fab")
			(hide yes)
			(effects
				(font
					(size 1 1)
					(thickness 0.15)
				)
			)
		)
		(property "Tolerance" "1%"
			(at 0 0 0)
			(unlocked yes)
			(layer "F.Fab")
			(hide yes)
			(effects
				(font
					(size 1 1)
					(thickness 0.15)
				)
			)
		)
		(sheetname "/PCIe-clock-generator/")
		(sheetfile "pcie-clock-generator.kicad_sch")
		(attr smd exclude_from_bom dnp)
		(fp_rect
			(start -0.925 -0.47)
			(end 0.925 0.47)
			(stroke
				(width 0.05)
				(type default)
			)
			(fill no)
			(layer "F.CrtYd")
		)
		(fp_rect
			(start -0.5 -0.25)
			(end 0.5 0.25)
			(stroke
				(width 0.15)
				(type solid)
			)
			(fill no)
			(layer "F.Fab")
		)
		(fp_text user "Author: Antmicro"
			(at -0.95 4.169 0)
			(layer "F.Fab")
			(effects
				(font
					(size 0.7 0.7)
					(thickness 0.15)
				)
				(justify left bottom)
			)
		)
		(fp_text user "${REFERENCE}"
			(at -0.95 3.168 0)
			(layer "F.Fab")
			(effects
				(font
					(size 0.7 0.7)
					(thickness 0.15)
				)
				(justify left bottom)
			)
		)
		(fp_text user "License: Apache-2.0"
			(at -0.95 5.169 0)
			(layer "F.Fab")
			(effects
				(font
					(size 0.7 0.7)
					(thickness 0.15)
				)
				(justify left bottom)
			)
		)
		(pad "1" smd roundrect
			(at -0.48 0)
			(size 0.59 0.64)
			(layers "F.Cu" "F.Mask" "F.Paste")
			(roundrect_rratio 0.25)
			(net 197 "/PCIe-clock-generator/PCIe_{REF1}_R2.CK+")
			(pintype "passive")
		)
		(pad "2" smd roundrect
			(at 0.48 0)
			(size 0.59 0.64)
			(layers "F.Cu" "F.Mask" "F.Paste")
			(roundrect_rratio 0.25)
			(net 178 "/PCIe-clock-generator/PCIe_{REF1}_R.CK+")
			(pintype "passive")
		)
	)
	(footprint "antmicro-footprints:R_0402_1005Metric"
		(layer "F.Cu")
		(at 120.5 127.8)
		(descr "Resistor SMD 0402")
		(tags "resistor SMD 0402")
		(property "Reference" "R6"
			(at -3.3 0.4 180)
			(layer "F.SilkS")
			(effects
				(font
					(size 0.7 0.7)
					(thickness 0.15)
				)
				(justify left bottom)
			)
		)
		(property "Value" "R_10k_0402"
			(at -1.011843 1.772046 0)
			(layer "F.Fab")
			(effects
				(font
					(size 0.7 0.7)
					(thickness 0.15)
				)
				(justify left bottom)
			)
		)
		(property "Datasheet" "https://www.bourns.com/docs/product-datasheets/cr.pdf"
			(at 0 0 0)
			(layer "F.Fab")
			(hide yes)
			(effects
				(font
					(size 1.27 1.27)
					(thickness 0.15)
				)
			)
		)
		(property "Description" "SMD Chip Resistor, 10 kohm, ± 1%, 62.5 mW, 0402 [1005 Metric], Thick Film, General Purpose"
			(at 0 0 0)
			(layer "F.Fab")
			(hide yes)
			(effects
				(font
					(size 1.27 1.27)
					(thickness 0.15)
				)
			)
		)
		(property "MPN" "CR0402-FX-1002GLF"
			(at 0 0 0)
			(unlocked yes)
			(layer "F.Fab")
			(hide yes)
			(effects
				(font
					(size 1 1)
					(thickness 0.15)
				)
			)
		)
		(property "Manufacturer" "Bourns"
			(at 0 0 0)
			(unlocked yes)
			(layer "F.Fab")
			(hide yes)
			(effects
				(font
					(size 1 1)
					(thickness 0.15)
				)
			)
		)
		(property "License" "Apache-2.0"
			(at 0 0 0)
			(unlocked yes)
			(layer "F.Fab")
			(hide yes)
			(effects
				(font
					(size 1 1)
					(thickness 0.15)
				)
			)
		)
		(property "Author" "Antmicro"
			(at 0 0 0)
			(unlocked yes)
			(layer "F.Fab")
			(hide yes)
			(effects
				(font
					(size 1 1)
					(thickness 0.15)
				)
			)
		)
		(property "Val" "10k"
			(at 0 0 0)
			(unlocked yes)
			(layer "F.Fab")
			(hide yes)
			(effects
				(font
					(size 1 1)
					(thickness 0.15)
				)
			)
		)
		(property "Tolerance" "1%"
			(at 0 0 0)
			(unlocked yes)
			(layer "F.Fab")
			(hide yes)
			(effects
				(font
					(size 1 1)
					(thickness 0.15)
				)
			)
		)
		(sheetname "/Power/")
		(sheetfile "power.kicad_sch")
		(attr smd)
		(fp_rect
			(start -0.925 -0.47)
			(end 0.925 0.47)
			(stroke
				(width 0.05)
				(type default)
			)
			(fill no)
			(layer "F.CrtYd")
		)
		(fp_rect
			(start -0.5 -0.25)
			(end 0.5 0.25)
			(stroke
				(width 0.15)
				(type solid)
			)
			(fill no)
			(layer "F.Fab")
		)
		(fp_text user "${REFERENCE}"
			(at 0 0 0)
			(layer "F.Fab")
			(effects
				(font
					(size 0.7 0.7)
					(thickness 0.15)
				)
				(justify left bottom)
			)
		)
		(fp_text user "License: Apache-2.0"
			(at -0.949999 5.169 0)
			(layer "F.Fab")
			(effects
				(font
					(size 0.7 0.7)
					(thickness 0.15)
				)
				(justify left bottom)
			)
		)
		(fp_text user "Author: Antmicro"
			(at -0.95 4.169 0)
			(layer "F.Fab")
			(effects
				(font
					(size 0.7 0.7)
					(thickness 0.15)
				)
				(justify left bottom)
			)
		)
		(pad "1" smd roundrect
			(at -0.48 0)
			(size 0.59 0.64)
			(layers "F.Cu" "F.Mask" "F.Paste")
			(roundrect_rratio 0.25)
			(net 88 "/Power/3V3_VCC")
			(pintype "passive")
		)
		(pad "2" smd roundrect
			(at 0.48 0)
			(size 0.59 0.64)
			(layers "F.Cu" "F.Mask" "F.Paste")
			(roundrect_rratio 0.25)
			(net 105 "/Power/3V3_PG")
			(pintype "passive")
		)
	)
	(footprint "antmicro-footprints:SOT-23-6"
		(layer "F.Cu")
		(at 141 144.5 90)
		(property "Reference" "U2"
			(at 0.7 -3.4 180)
			(layer "F.SilkS")
			(effects
				(font
					(size 0.7 0.7)
					(thickness 0.15)
				)
				(justify left bottom)
			)
		)
		(property "Value" "LTC4412IS6"
			(at -1.749999 2.693 90)
			(layer "F.Fab")
			(effects
				(font
					(size 0.7 0.7)
					(thickness 0.15)
				)
				(justify left bottom)
			)
		)
		(property "Datasheet" "https://www.analog.com/media/en/technical-documentation/data-sheets/4412fb.pdf"
			(at 0 -0.057 90)
			(layer "F.Fab")
			(hide yes)
			(effects
				(font
					(size 1.27 1.27)
					(thickness 0.15)
				)
			)
		)
		(property "Description" "Ideal diode controller"
			(at 0 -0.057 90)
			(layer "F.Fab")
			(hide yes)
			(effects
				(font
					(size 1.27 1.27)
					(thickness 0.15)
				)
			)
		)
		(property "MPN" "LTC4412IS6#TRMPBF"
			(at 0 0 90)
			(unlocked yes)
			(layer "F.Fab")
			(hide yes)
			(effects
				(font
					(size 1 1)
					(thickness 0.15)
				)
			)
		)
		(property "Manufacturer" "Analog Devices"
			(at 0 0 90)
			(unlocked yes)
			(layer "F.Fab")
			(hide yes)
			(effects
				(font
					(size 1 1)
					(thickness 0.15)
				)
			)
		)
		(property "Author" "Antmicro"
			(at 0 0 90)
			(unlocked yes)
			(layer "F.Fab")
			(hide yes)
			(effects
				(font
					(size 1 1)
					(thickness 0.15)
				)
			)
		)
		(property "License" "Apache-2.0"
			(at 0 0 90)
			(unlocked yes)
			(layer "F.Fab")
			(hide yes)
			(effects
				(font
					(size 1 1)
					(thickness 0.15)
				)
			)
		)
		(sheetname "/Power/Ideal-diode-2/")
		(sheetfile "ideal-diode.kicad_sch")
		(attr smd)
		(fp_line
			(start 1.45 -0.757)
			(end 1.45 -0.457)
			(stroke
				(width 0.12)
				(type solid)
			)
			(layer "F.SilkS")
		)
		(fp_line
			(start 1.3 -0.757)
			(end 1.45 -0.757)
			(stroke
				(width 0.12)
				(type solid)
			)
			(layer "F.SilkS")
		)
		(fp_line
			(start -1.3 -0.757)
			(end -1.45 -0.757)
			(stroke
				(width 0.12)
				(type solid)
			)
			(layer "F.SilkS")
		)
		(fp_line
			(start -1.45 -0.757)
			(end -1.45 -0.457)
			(stroke
				(width 0.12)
				(type solid)
			)
			(layer "F.SilkS")
		)
		(fp_line
			(start 1.45 0.643)
			(end 1.45 0.343)
			(stroke
				(width 0.12)
				(type solid)
			)
			(layer "F.SilkS")
		)
		(fp_line
			(start 1.3 0.643)
			(end 1.45 0.643)
			(stroke
				(width 0.12)
				(type solid)
			)
			(layer "F.SilkS")
		)
		(fp_line
			(start -1.45 0.643)
			(end -1.45 0.343)
			(stroke
				(width 0.12)
				(type solid)
			)
			(layer "F.SilkS")
		)
		(fp_rect
			(start -1.55 -1.85)
			(end 1.55 1.75)
			(stroke
				(width 0.05)
				(type solid)
			)
			(fill no)
			(layer "F.CrtYd")
		)
		(fp_line
			(start 1.5 -0.757)
			(end 1.5 0.643)
			(stroke
				(width 0.1)
				(type solid)
			)
			(layer "F.Fab")
		)
		(fp_line
			(start -1.5 -0.757)
			(end 1.5 -0.757)
			(stroke
				(width 0.1)
				(type solid)
			)
			(layer "F.Fab")
		)
		(fp_line
			(start 1.5 0.643)
			(end -1.5 0.643)
			(stroke
				(width 0.1)
				(type solid)
			)
			(layer "F.Fab")
		)
		(fp_line
			(start -1.5 0.643)
			(end -1.5 -0.757)
			(stroke
				(width 0.1)
				(type solid)
			)
			(layer "F.Fab")
		)
		(fp_text user "."
			(at -1.4 1.143001 90)
			(layer "F.SilkS")
			(effects
				(font
					(size 1 1)
					(thickness 0.15)
				)
			)
		)
		(fp_text user "Author: Antmicro"
			(at -1.829 5.25 90)
			(layer "F.Fab")
			(effects
				(font
					(size 0.7 0.7)
					(thickness 0.15)
				)
				(justify left bottom)
			)
		)
		(fp_text user "${REFERENCE}"
			(at 0 -0.05 90)
			(layer "F.Fab")
			(effects
				(font
					(size 0.7 0.7)
					(thickness 0.15)
				)
				(justify left bottom)
			)
		)
		(fp_text user "License: Apache-2.0"
			(at -1.75 6.5 90)
			(layer "F.Fab")
			(effects
				(font
					(size 0.7 0.7)
					(thickness 0.15)
				)
				(justify left bottom)
			)
		)
		(pad "1" smd roundrect
			(at -0.954 1.1 90)
			(size 0.55 1)
			(layers "F.Cu" "F.Mask" "F.Paste")
			(roundrect_rratio 0.15)
			(net 116 "/Power/Ideal-diode-2/VIN")
			(pinfunction "IN")
			(pintype "power_in")
		)
		(pad "2" smd roundrect
			(at -0.003 1.1 90)
			(size 0.55 1)
			(layers "F.Cu" "F.Mask" "F.Paste")
			(roundrect_rratio 0.15)
			(net 66 "GND")
			(pinfunction "GND")
			(pintype "power_in")
		)
		(pad "3" smd roundrect
			(at 0.947 1.1 90)
			(size 0.55 1)
			(layers "F.Cu" "F.Mask" "F.Paste")
			(roundrect_rratio 0.15)
			(net 66 "GND")
			(pinfunction "CTL")
			(pintype "input")
		)
		(pad "4" smd roundrect
			(at 0.947 -1.214 90)
			(size 0.55 1)
			(layers "F.Cu" "F.Mask" "F.Paste")
			(roundrect_rratio 0.15)
			(net 180 "unconnected-(U2-STAT-Pad4)")
			(pinfunction "STAT")
			(pintype "output+no_connect")
		)
		(pad "5" smd roundrect
			(at -0.003 -1.214 90)
			(size 0.55 1)
			(layers "F.Cu" "F.Mask" "F.Paste")
			(roundrect_rratio 0.15)
			(net 175 "Net-(Q7-G)")
			(pinfunction "GATE")
			(pintype "output")
		)
		(pad "6" smd roundrect
			(at -0.954 -1.214 90)
			(size 0.55 1)
			(layers "F.Cu" "F.Mask" "F.Paste")
			(roundrect_rratio 0.15)
			(net 87 "+12V")
			(pinfunction "SENSE")
			(pintype "input")
		)
	)
)
